(kicad_pcb
	(version 20260206)
	(generator "pcbnew")
	(generator_version "10.0")
	(general
		(thickness 1.6)
		(legacy_teardrops no)
	)
	(paper "A4")
	(title_block
		(title "Bryce Canyon_SCC_16316-1_OCP.brd")
		(comment 1 "Bryce Canyon / footprints 1136-1143 of 1561")
	)
	(layers
		(0 "F.Cu" signal "TOP")
		(4 "In1.Cu" signal "L2GND")
		(6 "In2.Cu" signal "L3")
		(8 "In3.Cu" signal "L4VCC")
		(10 "In4.Cu" signal "L5VCC")
		(12 "In5.Cu" signal "L6")
		(14 "In6.Cu" signal "L7GND")
		(2 "B.Cu" signal "BOTTOM")
		(9 "F.Adhes" user "F.Adhesive")
		(11 "B.Adhes" user "B.Adhesive")
		(13 "F.Paste" user "Package Geometry/Pastemask Top")
		(15 "B.Paste" user "Package Geometry/Pastemask Bottom")
		(5 "F.SilkS" user "Ref Des/Silkscreen Top")
		(7 "B.SilkS" user "Ref Des/Silkscreen Bottom")
		(1 "F.Mask" user "Board Geometry/Soldermask Top")
		(3 "B.Mask" user "Board Geometry/Soldermask Bottom")
		(17 "Dwgs.User" user "User.Drawings")
		(19 "Cmts.User" user "User.Comments")
		(21 "Eco1.User" user "User.Eco1")
		(23 "Eco2.User" user "User.Eco2")
		(25 "Edge.Cuts" user "Board Geometry/Outline")
		(27 "Margin" user)
		(31 "F.CrtYd" user "Package Geometry/Place Bound Top")
		(29 "B.CrtYd" user "Package Geometry/Place Bound Bottom")
		(35 "F.Fab" user "Ref Des/Assembly Top")
		(33 "B.Fab" user "Ref Des/Assembly Bottom")
	)
	(footprint ""
		(layer "B.Cu")
		(at 118.531132 -70.427596 180)
		(property "Reference" "C189"
			(at 0 0 0)
			(layer "B.SilkS")
			(hide yes)
			(effects
				(font
					(size 1.27 1.27)
				)
				(justify mirror)
			)
		)
		(property "Value" "SC1KP25V1KX-GP"
			(at 2.8321 -1.7399 180)
			(unlocked yes)
			(layer "B.Fab")
			(hide yes)
			(effects
				(font
					(size 1.016 1.016)
					(thickness 0.1524)
				)
				(justify mirror)
			)
		)
		(property "Device Type" "C0201H13"
			(at 2.8321 -3.2639 180)
			(unlocked yes)
			(layer "B.Fab")
			(hide yes)
			(effects
				(font
					(size 1.016 1.016)
					(thickness 0.1524)
				)
				(justify mirror)
			)
		)
		(duplicate_pad_numbers_are_jumpers no)
		(fp_rect
			(start 0.2794 0.6477)
			(end -0.2794 -0.6477)
			(stroke
				(width 0)
				(type default)
			)
			(fill no)
			(layer "B.CrtYd")
		)
		(fp_rect
			(start 0.2794 0.6477)
			(end -0.2794 -0.6477)
			(stroke
				(width 0)
				(type default)
			)
			(fill no)
			(layer "B.Fab")
		)
		(pad "1" smd custom
			(at 0 -0.2794)
			(size 0.0762 0.0762)
			(layers "B.Cu" "B.Mask" "B.Paste")
			(net "P0V9")
			(options
				(clearance outline)
				(anchor circle)
			)
			(primitives
				(gr_poly
					(pts
						(arc
							(start 0.1524 0.127)
							(mid 0.137521 0.162921)
							(end 0.1016 0.1778)
						)
						(arc
							(start -0.1016 0.1778)
							(mid -0.137521 0.162921)
							(end -0.1524 0.127)
						)
						(arc
							(start -0.1524 -0.127)
							(mid -0.137521 -0.162921)
							(end -0.1016 -0.1778)
						)
						(arc
							(start 0.1016 -0.1778)
							(mid 0.137521 -0.162921)
							(end 0.1524 -0.127)
						)
					)
					(width 0)
					(fill yes)
				)
			)
		)
		(pad "2" smd custom
			(at 0 0.2794)
			(size 0.0762 0.0762)
			(layers "B.Cu" "B.Mask" "B.Paste")
			(net "GND")
			(options
				(clearance outline)
				(anchor circle)
			)
			(primitives
				(gr_poly
					(pts
						(arc
							(start 0.1524 0.127)
							(mid 0.137521 0.162921)
							(end 0.1016 0.1778)
						)
						(arc
							(start -0.1016 0.1778)
							(mid -0.137521 0.162921)
							(end -0.1524 0.127)
						)
						(arc
							(start -0.1524 -0.127)
							(mid -0.137521 -0.162921)
							(end -0.1016 -0.1778)
						)
						(arc
							(start 0.1016 -0.1778)
							(mid 0.137521 -0.162921)
							(end 0.1524 -0.127)
						)
					)
					(width 0)
					(fill yes)
				)
			)
		)
	)
	(footprint ""
		(layer "B.Cu")
		(at 104.504744 -62.23)
		(property "Reference" "C202"
			(at 0 0 0)
			(layer "B.SilkS")
			(hide yes)
			(effects
				(font
					(size 1.27 1.27)
				)
				(justify mirror)
			)
		)
		(property "Value" "SC1U6D3V1MX-GP"
			(at -1.9177 2.0193 0)
			(unlocked yes)
			(layer "B.Fab")
			(hide yes)
			(effects
				(font
					(size 1.016 1.016)
					(thickness 0.1524)
				)
				(justify mirror)
			)
		)
		(property "Device Type" "C0201H14"
			(at -1.9177 0.4953 0)
			(unlocked yes)
			(layer "B.Fab")
			(hide yes)
			(effects
				(font
					(size 1.016 1.016)
					(thickness 0.1524)
				)
				(justify mirror)
			)
		)
		(duplicate_pad_numbers_are_jumpers no)
		(fp_rect
			(start 0.1524 0.3048)
			(end -0.1524 -0.3048)
			(stroke
				(width 0)
				(type default)
			)
			(fill no)
			(layer "B.CrtYd")
		)
		(fp_poly
			(pts
				(xy 0.2794 0.6477) (xy 0.2794 -0.6477) (xy -0.2794 -0.6477) (xy -0.2794 -0.1905) (xy -0.1524 -0.1905)
				(xy -0.1524 -0.3048) (xy 0.1524 -0.3048) (xy 0.1524 0.3048) (xy -0.1524 0.3048) (xy -0.1524 -0.1778)
				(xy -0.2794 -0.1778) (xy -0.2794 0.6477)
			)
			(stroke
				(width 0)
				(type default)
			)
			(fill no)
			(layer "B.CrtYd")
		)
		(fp_rect
			(start 0.2794 0.6477)
			(end -0.2794 -0.6477)
			(stroke
				(width 0)
				(type default)
			)
			(fill no)
			(layer "B.Fab")
		)
		(pad "1" smd custom
			(at 0 -0.2794 180)
			(size 0.0762 0.0762)
			(layers "B.Cu" "B.Mask" "B.Paste")
			(net "PLLDDR_VDDA18")
			(options
				(clearance outline)
				(anchor circle)
			)
			(primitives
				(gr_poly
					(pts
						(arc
							(start 0.1524 0.127)
							(mid 0.137521 0.162921)
							(end 0.1016 0.1778)
						)
						(arc
							(start -0.1016 0.1778)
							(mid -0.137521 0.162921)
							(end -0.1524 0.127)
						)
						(arc
							(start -0.1524 -0.127)
							(mid -0.137521 -0.162921)
							(end -0.1016 -0.1778)
						)
						(arc
							(start 0.1016 -0.1778)
							(mid 0.137521 -0.162921)
							(end 0.1524 -0.127)
						)
					)
					(width 0)
					(fill yes)
				)
			)
		)
		(pad "2" smd custom
			(at 0 0.2794 180)
			(size 0.0762 0.0762)
			(layers "B.Cu" "B.Mask" "B.Paste")
			(net "GND")
			(options
				(clearance outline)
				(anchor circle)
			)
			(primitives
				(gr_poly
					(pts
						(arc
							(start 0.1524 0.127)
							(mid 0.137521 0.162921)
							(end 0.1016 0.1778)
						)
						(arc
							(start -0.1016 0.1778)
							(mid -0.137521 0.162921)
							(end -0.1524 0.127)
						)
						(arc
							(start -0.1524 -0.127)
							(mid -0.137521 -0.162921)
							(end -0.1016 -0.1778)
						)
						(arc
							(start 0.1016 -0.1778)
							(mid 0.137521 -0.162921)
							(end 0.1524 -0.127)
						)
					)
					(width 0)
					(fill yes)
				)
			)
		)
	)
	(footprint ""
		(layer "B.Cu")
		(at 109.33938 -61.488066)
		(property "Reference" "C225"
			(at 0 0 0)
			(layer "B.SilkS")
			(hide yes)
			(effects
				(font
					(size 1.27 1.27)
				)
				(justify mirror)
			)
		)
		(property "Value" "SCD1U16V2KX-3GP"
			(at -1.1811 -2.7051 0)
			(unlocked yes)
			(layer "B.Fab")
			(hide yes)
			(effects
				(font
					(size 1.016 1.016)
					(thickness 0.1524)
				)
				(justify mirror)
			)
		)
		(property "Device Type" "C402H22"
			(at -1.1811 -4.2291 0)
			(unlocked yes)
			(layer "B.Fab")
			(hide yes)
			(effects
				(font
					(size 1.016 1.016)
					(thickness 0.1524)
				)
				(justify mirror)
			)
		)
		(duplicate_pad_numbers_are_jumpers no)
		(fp_rect
			(start 0.4318 0.9525)
			(end -0.4318 -0.9525)
			(stroke
				(width 0)
				(type default)
			)
			(fill no)
			(layer "B.CrtYd")
		)
		(fp_rect
			(start 0.4318 0.9525)
			(end -0.4318 -0.9525)
			(stroke
				(width 0)
				(type default)
			)
			(fill no)
			(layer "B.Fab")
		)
		(pad "1" smd custom
			(at 0 -0.4445 180)
			(size 0.1524 0.1524)
			(layers "B.Cu" "B.Mask" "B.Paste")
			(net "GB_VDDH")
			(options
				(clearance outline)
				(anchor circle)
			)
			(primitives
				(gr_poly
					(pts
						(arc
							(start 0.3048 0.2032)
							(mid 0.275042 0.275042)
							(end 0.2032 0.3048)
						)
						(arc
							(start -0.2032 0.3048)
							(mid -0.275042 0.275042)
							(end -0.3048 0.2032)
						)
						(arc
							(start -0.3048 -0.2032)
							(mid -0.275042 -0.275042)
							(end -0.2032 -0.3048)
						)
						(arc
							(start 0.2032 -0.3048)
							(mid 0.275042 -0.275042)
							(end 0.3048 -0.2032)
						)
					)
					(width 0)
					(fill yes)
				)
			)
		)
		(pad "2" smd custom
			(at 0 0.4445 180)
			(size 0.1524 0.1524)
			(layers "B.Cu" "B.Mask" "B.Paste")
			(net "GND")
			(options
				(clearance outline)
				(anchor circle)
			)
			(primitives
				(gr_poly
					(pts
						(arc
							(start 0.3048 0.2032)
							(mid 0.275042 0.275042)
							(end 0.2032 0.3048)
						)
						(arc
							(start -0.2032 0.3048)
							(mid -0.275042 0.275042)
							(end -0.3048 0.2032)
						)
						(arc
							(start -0.3048 -0.2032)
							(mid -0.275042 -0.275042)
							(end -0.2032 -0.3048)
						)
						(arc
							(start 0.2032 -0.3048)
							(mid 0.275042 -0.275042)
							(end 0.3048 -0.2032)
						)
					)
					(width 0)
					(fill yes)
				)
			)
		)
	)
	(footprint ""
		(layer "B.Cu")
		(at 187.2234 -26.162 90)
		(property "Reference" "TP72"
			(at 0 0 90)
			(layer "B.SilkS")
			(hide yes)
			(effects
				(font
					(size 1.27 1.27)
				)
				(justify mirror)
			)
		)
		(property "Value" "TPAD28-2-GP"
			(at 0.0127 -1.6637 90)
			(unlocked yes)
			(layer "B.Fab")
			(hide yes)
			(effects
				(font
					(size 1.016 1.016)
					(thickness 0.1524)
				)
				(justify mirror)
			)
		)
		(property "Device Type" "TPAD28"
			(at 0.0127 -3.1877 90)
			(unlocked yes)
			(layer "B.Fab")
			(hide yes)
			(effects
				(font
					(size 1.016 1.016)
					(thickness 0.1524)
				)
				(justify mirror)
			)
		)
		(duplicate_pad_numbers_are_jumpers no)
		(fp_poly
			(pts
				(arc
					(start 0 0.3556)
					(mid 0 -0.3556)
					(end 0 0.3556)
				)
			)
			(stroke
				(width 0)
				(type default)
			)
			(fill no)
			(layer "B.CrtYd")
		)
		(fp_poly
			(pts
				(arc
					(start 0 0.6096)
					(mid 0 -0.6096)
					(end 0 0.6096)
				)
			)
			(stroke
				(width 0)
				(type default)
			)
			(fill no)
			(layer "B.Fab")
		)
		(pad "1" smd circle
			(at 0 0 270)
			(size 0.7112 0.7112)
			(layers "B.Cu" "B.Mask" "B.Paste")
			(net "IOC_GPIO_19")
		)
	)
	(footprint ""
		(layer "B.Cu")
		(at 93.262958 -78.323948)
		(property "Reference" "C209"
			(at 0 0 0)
			(layer "B.SilkS")
			(hide yes)
			(effects
				(font
					(size 1.27 1.27)
				)
				(justify mirror)
			)
		)
		(property "Value" "SC10U6D3V2MX-GP-U"
			(at 1.524 -1.905 0)
			(unlocked yes)
			(layer "B.Fab")
			(hide yes)
			(effects
				(font
					(size 1.016 1.016)
					(thickness 0.1524)
				)
				(justify mirror)
			)
		)
		(property "Device Type" "C402-TO0D2H28"
			(at 1.524 -3.429 0)
			(unlocked yes)
			(layer "B.Fab")
			(hide yes)
			(effects
				(font
					(size 1.016 1.016)
					(thickness 0.1524)
				)
				(justify mirror)
			)
		)
		(duplicate_pad_numbers_are_jumpers no)
		(fp_rect
			(start 0.4826 0.889)
			(end -0.4826 -0.889)
			(stroke
				(width 0)
				(type default)
			)
			(fill no)
			(layer "B.CrtYd")
		)
		(fp_rect
			(start 0.4826 0.889)
			(end -0.4826 -0.889)
			(stroke
				(width 0)
				(type default)
			)
			(fill no)
			(layer "B.Fab")
		)
		(pad "1" smd custom
			(at 0 -0.4572 180)
			(size 0.1524 0.1524)
			(layers "B.Cu" "B.Mask" "B.Paste")
			(net "SYSPLL_VDDA09")
			(options
				(clearance outline)
				(anchor circle)
			)
			(primitives
				(gr_poly
					(pts
						(arc
							(start -0.254 -0.3048)
							(mid -0.325842 -0.275042)
							(end -0.3556 -0.2032)
						)
						(arc
							(start -0.3556 0.2032)
							(mid -0.325842 0.275042)
							(end -0.254 0.3048)
						)
						(arc
							(start 0.254 0.3048)
							(mid 0.325842 0.275042)
							(end 0.3556 0.2032)
						)
						(arc
							(start 0.3556 -0.2032)
							(mid 0.325842 -0.275042)
							(end 0.254 -0.3048)
						)
					)
					(width 0)
					(fill yes)
				)
			)
		)
		(pad "2" smd custom
			(at 0 0.4572 180)
			(size 0.1524 0.1524)
			(layers "B.Cu" "B.Mask" "B.Paste")
			(net "GND")
			(options
				(clearance outline)
				(anchor circle)
			)
			(primitives
				(gr_poly
					(pts
						(arc
							(start -0.254 -0.3048)
							(mid -0.325842 -0.275042)
							(end -0.3556 -0.2032)
						)
						(arc
							(start -0.3556 0.2032)
							(mid -0.325842 0.275042)
							(end -0.254 0.3048)
						)
						(arc
							(start 0.254 0.3048)
							(mid 0.325842 0.275042)
							(end 0.3556 0.2032)
						)
						(arc
							(start 0.3556 -0.2032)
							(mid 0.325842 -0.275042)
							(end 0.254 -0.3048)
						)
					)
					(width 0)
					(fill yes)
				)
			)
		)
	)
	(footprint ""
		(layer "B.Cu")
		(at 176.1617 -42.9133 90)
		(property "Reference" "C432"
			(at 0 0 90)
			(layer "B.SilkS")
			(hide yes)
			(effects
				(font
					(size 1.27 1.27)
				)
				(justify mirror)
			)
		)
		(property "Value" "SCD1U6D3V1KX-GP"
			(at 2.8321 -1.7399 90)
			(unlocked yes)
			(layer "B.Fab")
			(hide yes)
			(effects
				(font
					(size 1.016 1.016)
					(thickness 0.1524)
				)
				(justify mirror)
			)
		)
		(property "Device Type" "C0201H13"
			(at 2.8321 -3.2639 90)
			(unlocked yes)
			(layer "B.Fab")
			(hide yes)
			(effects
				(font
					(size 1.016 1.016)
					(thickness 0.1524)
				)
				(justify mirror)
			)
		)
		(duplicate_pad_numbers_are_jumpers no)
		(fp_rect
			(start 0.2794 0.6477)
			(end -0.2794 -0.6477)
			(stroke
				(width 0)
				(type default)
			)
			(fill no)
			(layer "B.CrtYd")
		)
		(fp_rect
			(start 0.2794 0.6477)
			(end -0.2794 -0.6477)
			(stroke
				(width 0)
				(type default)
			)
			(fill no)
			(layer "B.Fab")
		)
		(pad "1" smd custom
			(at 0 -0.2794 270)
			(size 0.0762 0.0762)
			(layers "B.Cu" "B.Mask" "B.Paste")
			(net "P0V975")
			(options
				(clearance outline)
				(anchor circle)
			)
			(primitives
				(gr_poly
					(pts
						(arc
							(start 0.1524 0.127)
							(mid 0.137521 0.162921)
							(end 0.1016 0.1778)
						)
						(arc
							(start -0.1016 0.1778)
							(mid -0.137521 0.162921)
							(end -0.1524 0.127)
						)
						(arc
							(start -0.1524 -0.127)
							(mid -0.137521 -0.162921)
							(end -0.1016 -0.1778)
						)
						(arc
							(start 0.1016 -0.1778)
							(mid 0.137521 -0.162921)
							(end 0.1524 -0.127)
						)
					)
					(width 0)
					(fill yes)
				)
			)
		)
		(pad "2" smd custom
			(at 0 0.2794 270)
			(size 0.0762 0.0762)
			(layers "B.Cu" "B.Mask" "B.Paste")
			(net "GND")
			(options
				(clearance outline)
				(anchor circle)
			)
			(primitives
				(gr_poly
					(pts
						(arc
							(start 0.1524 0.127)
							(mid 0.137521 0.162921)
							(end 0.1016 0.1778)
						)
						(arc
							(start -0.1016 0.1778)
							(mid -0.137521 0.162921)
							(end -0.1524 0.127)
						)
						(arc
							(start -0.1524 -0.127)
							(mid -0.137521 -0.162921)
							(end -0.1016 -0.1778)
						)
						(arc
							(start 0.1016 -0.1778)
							(mid 0.137521 -0.162921)
							(end 0.1524 -0.127)
						)
					)
					(width 0)
					(fill yes)
				)
			)
		)
	)
	(footprint ""
		(layer "B.Cu")
		(at 70.612 -35.814 90)
		(property "Reference" "R157"
			(at 0 0 90)
			(layer "B.SilkS")
			(hide yes)
			(effects
				(font
					(size 1.27 1.27)
				)
				(justify mirror)
			)
		)
		(property "Value" "D51R3F-2-GP"
			(at 0.0254 -2.5146 90)
			(unlocked yes)
			(layer "B.Fab")
			(hide yes)
			(effects
				(font
					(size 1.016 1.016)
					(thickness 0.1524)
				)
				(justify mirror)
			)
		)
		(property "Device Type" "R603H22"
			(at 0.0254 -4.0386 90)
			(unlocked yes)
			(layer "B.Fab")
			(hide yes)
			(effects
				(font
					(size 1.016 1.016)
					(thickness 0.1524)
				)
				(justify mirror)
			)
		)
		(duplicate_pad_numbers_are_jumpers no)
		(fp_line
			(start 0.4826 0)
			(end 0.2032 0)
			(stroke
				(width 0.2032)
				(type default)
			)
			(layer "B.SilkS")
		)
		(fp_line
			(start -0.2032 0)
			(end -0.4826 0)
			(stroke
				(width 0.2032)
				(type default)
			)
			(layer "B.SilkS")
		)
		(fp_rect
			(start 0.5842 1.3335)
			(end -0.5842 -1.3335)
			(stroke
				(width 0)
				(type default)
			)
			(fill no)
			(layer "B.CrtYd")
		)
		(fp_rect
			(start 0.5842 1.3335)
			(end -0.5842 -1.3335)
			(stroke
				(width 0)
				(type default)
			)
			(fill no)
			(layer "B.Fab")
		)
		(pad "1" smd custom
			(at 0 -0.762 270)
			(size 0.2159 0.2159)
			(layers "B.Cu" "B.Mask" "B.Paste")
			(net "P0V9")
			(options
				(clearance outline)
				(anchor circle)
			)
			(primitives
				(gr_poly
					(pts
						(arc
							(start -0.3302 0.4318)
							(mid -0.402042 0.402042)
							(end -0.4318 0.3302)
						)
						(arc
							(start -0.4318 -0.3302)
							(mid -0.402042 -0.402042)
							(end -0.3302 -0.4318)
						)
						(arc
							(start 0.3302 -0.4318)
							(mid 0.402042 -0.402042)
							(end 0.4318 -0.3302)
						)
						(arc
							(start 0.4318 0.3302)
							(mid 0.402042 0.402042)
							(end 0.3302 0.4318)
						)
					)
					(width 0)
					(fill yes)
				)
			)
		)
		(pad "2" smd custom
			(at 0 0.762 270)
			(size 0.2159 0.2159)
			(layers "B.Cu" "B.Mask" "B.Paste")
			(net "GB_VDDA")
			(options
				(clearance outline)
				(anchor circle)
			)
			(primitives
				(gr_poly
					(pts
						(arc
							(start -0.3302 0.4318)
							(mid -0.402042 0.402042)
							(end -0.4318 0.3302)
						)
						(arc
							(start -0.4318 -0.3302)
							(mid -0.402042 -0.402042)
							(end -0.3302 -0.4318)
						)
						(arc
							(start 0.3302 -0.4318)
							(mid 0.402042 -0.402042)
							(end 0.4318 -0.3302)
						)
						(arc
							(start 0.4318 0.3302)
							(mid 0.402042 0.402042)
							(end 0.3302 0.4318)
						)
					)
					(width 0)
					(fill yes)
				)
			)
		)
	)
	(footprint ""
		(layer "B.Cu")
		(at 175.611028 -20.954746)
		(property "Reference" "C322"
			(at 0 0 0)
			(layer "B.SilkS")
			(hide yes)
			(effects
				(font
					(size 1.27 1.27)
				)
				(justify mirror)
			)
		)
		(property "Value" "SCD22U10V1KX-GP"
			(at 2.8321 -1.7399 0)
			(unlocked yes)
			(layer "B.Fab")
			(hide yes)
			(effects
				(font
					(size 1.016 1.016)
					(thickness 0.1524)
				)
				(justify mirror)
			)
		)
		(property "Device Type" "C0201H13"
			(at 2.8321 -3.2639 0)
			(unlocked yes)
			(layer "B.Fab")
			(hide yes)
			(effects
				(font
					(size 1.016 1.016)
					(thickness 0.1524)
				)
				(justify mirror)
			)
		)
		(duplicate_pad_numbers_are_jumpers no)
		(fp_rect
			(start 0.2794 0.6477)
			(end -0.2794 -0.6477)
			(stroke
				(width 0)
				(type default)
			)
			(fill no)
			(layer "B.CrtYd")
		)
		(fp_rect
			(start 0.2794 0.6477)
			(end -0.2794 -0.6477)
			(stroke
				(width 0)
				(type default)
			)
			(fill no)
			(layer "B.Fab")
		)
		(pad "1" smd custom
			(at 0 -0.2794 180)
			(size 0.0762 0.0762)
			(layers "B.Cu" "B.Mask" "B.Paste")
			(net "PCIE_SCC_TO_COMP_C_5_DN")
			(options
				(clearance outline)
				(anchor circle)
			)
			(primitives
				(gr_poly
					(pts
						(arc
							(start 0.1524 0.127)
							(mid 0.137521 0.162921)
							(end 0.1016 0.1778)
						)
						(arc
							(start -0.1016 0.1778)
							(mid -0.137521 0.162921)
							(end -0.1524 0.127)
						)
						(arc
							(start -0.1524 -0.127)
							(mid -0.137521 -0.162921)
							(end -0.1016 -0.1778)
						)
						(arc
							(start 0.1016 -0.1778)
							(mid 0.137521 -0.162921)
							(end 0.1524 -0.127)
						)
					)
					(width 0)
					(fill yes)
				)
			)
		)
		(pad "2" smd custom
			(at 0 0.2794 180)
			(size 0.0762 0.0762)
			(layers "B.Cu" "B.Mask" "B.Paste")
			(net "PCIE_SCC_TO_COMP_5_DN")
			(options
				(clearance outline)
				(anchor circle)
			)
			(primitives
				(gr_poly
					(pts
						(arc
							(start 0.1524 0.127)
							(mid 0.137521 0.162921)
							(end 0.1016 0.1778)
						)
						(arc
							(start -0.1016 0.1778)
							(mid -0.137521 0.162921)
							(end -0.1524 0.127)
						)
						(arc
							(start -0.1524 -0.127)
							(mid -0.137521 -0.162921)
							(end -0.1016 -0.1778)
						)
						(arc
							(start 0.1016 -0.1778)
							(mid 0.137521 -0.162921)
							(end 0.1524 -0.127)
						)
					)
					(width 0)
					(fill yes)
				)
			)
		)
	)
)
